(kicad_pcb
	(version 20241229)
	(generator "pcbnew")
	(generator_version "9.0")
	(general
		(thickness 1.6)
		(legacy_teardrops no)
	)
	(paper "A4")
	(title_block
		(title "GMSL Deserializer")
		(date "2025-10-09")
		(rev "1.0.4")
		(company "Antmicro Ltd")
		(comment 1 "www.antmicro.com")
		(comment 9 "footprints 139-143 of 235")
	)
	(layers
		(0 "F.Cu" signal)
		(4 "In1.Cu" power)
		(6 "In2.Cu" power)
		(2 "B.Cu" signal)
		(9 "F.Adhes" user "F.Adhesive")
		(11 "B.Adhes" user "B.Adhesive")
		(13 "F.Paste" user)
		(15 "B.Paste" user)
		(5 "F.SilkS" user "F.Silkscreen")
		(7 "B.SilkS" user "B.Silkscreen")
		(1 "F.Mask" user)
		(3 "B.Mask" user)
		(17 "Dwgs.User" user "User.Drawings")
		(19 "Cmts.User" user "User.Comments")
		(21 "Eco1.User" user "User.Eco1")
		(23 "Eco2.User" user "User.Eco2")
		(25 "Edge.Cuts" user)
		(27 "Margin" user)
		(31 "F.CrtYd" user "F.Courtyard")
		(29 "B.CrtYd" user "B.Courtyard")
		(35 "F.Fab" user)
		(33 "B.Fab" user)
	)
	(footprint "antmicro-footprints:TSSOP-8_3x3mm_P0.65mm"
		(layer "F.Cu")
		(at 176.196 62.584 -90)
		(property "Reference" "U8"
			(at -3.406179 -2.154 90)
			(layer "F.SilkS")
			(effects
				(font
					(size 0.7 0.7)
					(thickness 0.15)
				)
				(justify right bottom)
			)
		)
		(property "Value" "NTS0102_TSSOP"
			(at 0 2.8 90)
			(layer "F.Fab")
			(effects
				(font
					(size 0.7 0.7)
					(thickness 0.15)
				)
				(justify right bottom)
			)
		)
		(property "Datasheet" "https://www.mouser.com/datasheet/2/302/NTS0102-1127324.pdf"
			(at 0 0 270)
			(layer "F.Fab")
			(hide yes)
			(effects
				(font
					(size 1.27 1.27)
					(thickness 0.15)
				)
			)
		)
		(property "Description" "Transceiver, 1.65 V to 3.6 V, TSSOP-8"
			(at 0 0 270)
			(layer "F.Fab")
			(hide yes)
			(effects
				(font
					(size 1.27 1.27)
					(thickness 0.15)
				)
			)
		)
		(property "Author" "Antmicro"
			(at 113.612 238.78 0)
			(layer "F.Fab")
			(hide yes)
			(effects
				(font
					(size 1 1)
					(thickness 0.15)
				)
			)
		)
		(property "License" "Apache-2.0"
			(at 113.612 238.78 0)
			(layer "F.Fab")
			(hide yes)
			(effects
				(font
					(size 1 1)
					(thickness 0.15)
				)
			)
		)
		(property "MPN" "NTS0102DP"
			(at 113.612 238.78 0)
			(layer "F.Fab")
			(hide yes)
			(effects
				(font
					(size 1 1)
					(thickness 0.15)
				)
			)
		)
		(property "Manufacturer" "NXP"
			(at 113.612 238.78 0)
			(layer "F.Fab")
			(hide yes)
			(effects
				(font
					(size 1 1)
					(thickness 0.15)
				)
			)
		)
		(sheetname "/Connectors/")
		(sheetfile "connectors.kicad_sch")
		(attr smd)
		(fp_line
			(start -1.55 1.561)
			(end 1.552 1.561)
			(stroke
				(width 0.15)
				(type solid)
			)
			(layer "F.SilkS")
		)
		(fp_line
			(start -1.525 -1.537)
			(end 1.552 -1.539)
			(stroke
				(width 0.15)
				(type solid)
			)
			(layer "F.SilkS")
		)
		(fp_circle
			(center -1.87 -1.4)
			(end -1.82 -1.4)
			(stroke
				(width 0.15)
				(type solid)
			)
			(fill yes)
			(layer "F.SilkS")
		)
		(fp_rect
			(start -3.15 -1.789)
			(end 3.15 1.811)
			(stroke
				(width 0.05)
				(type solid)
			)
			(fill no)
			(layer "F.CrtYd")
		)
		(fp_line
			(start -1.55 1.561)
			(end 1.552 1.561)
			(stroke
				(width 0.15)
				(type solid)
			)
			(layer "F.Fab")
		)
		(fp_line
			(start -1.55 -0.937)
			(end -1.55 1.561)
			(stroke
				(width 0.15)
				(type solid)
			)
			(layer "F.Fab")
		)
		(fp_line
			(start -1.55 -0.937)
			(end -0.949 -1.539)
			(stroke
				(width 0.15)
				(type solid)
			)
			(layer "F.Fab")
		)
		(fp_line
			(start -0.949 -1.539)
			(end 1.552 -1.539)
			(stroke
				(width 0.15)
				(type solid)
			)
			(layer "F.Fab")
		)
		(fp_line
			(start 1.552 -1.539)
			(end 1.552 1.561)
			(stroke
				(width 0.15)
				(type solid)
			)
			(layer "F.Fab")
		)
		(pad "1" smd roundrect
			(at -2.148 -0.962 270)
			(size 1.47 0.4)
			(layers "F.Cu" "F.Mask" "F.Paste")
			(roundrect_rratio 0.25)
			(net 45 "/Connectors/SCL_CAM")
			(pinfunction "B_{2}")
			(pintype "bidirectional")
		)
		(pad "2" smd roundrect
			(at -2.148 -0.313 270)
			(size 1.47 0.4)
			(layers "F.Cu" "F.Mask" "F.Paste")
			(roundrect_rratio 0.25)
			(net 1 "GND")
			(pinfunction "GND")
			(pintype "power_in")
		)
		(pad "3" smd roundrect
			(at -2.148 0.338 270)
			(size 1.47 0.4)
			(layers "F.Cu" "F.Mask" "F.Paste")
			(roundrect_rratio 0.25)
			(net 3 "+1V8")
			(pinfunction "VCC_{A}")
			(pintype "power_in")
		)
		(pad "4" smd roundrect
			(at -2.148 0.987 270)
			(size 1.47 0.4)
			(layers "F.Cu" "F.Mask" "F.Paste")
			(roundrect_rratio 0.25)
			(net 134 "Net-(U8-A_{2})")
			(pinfunction "A_{2}")
			(pintype "bidirectional")
		)
		(pad "5" smd roundrect
			(at 2.151 0.987 270)
			(size 1.47 0.4)
			(layers "F.Cu" "F.Mask" "F.Paste")
			(roundrect_rratio 0.25)
			(net 133 "Net-(U8-A_{1})")
			(pinfunction "A_{1}")
			(pintype "bidirectional")
		)
		(pad "6" smd roundrect
			(at 2.151 0.338 270)
			(size 1.47 0.4)
			(layers "F.Cu" "F.Mask" "F.Paste")
			(roundrect_rratio 0.25)
			(net 135 "Net-(U8-OE)")
			(pinfunction "OE")
			(pintype "input")
		)
		(pad "7" smd roundrect
			(at 2.151 -0.313 270)
			(size 1.47 0.4)
			(layers "F.Cu" "F.Mask" "F.Paste")
			(roundrect_rratio 0.25)
			(net 50 "/Connectors/FFC_3V3")
			(pinfunction "VCC_{B}")
			(pintype "power_in")
		)
		(pad "8" smd roundrect
			(at 2.151 -0.962 270)
			(size 1.47 0.4)
			(layers "F.Cu" "F.Mask" "F.Paste")
			(roundrect_rratio 0.25)
			(net 44 "/Connectors/SDA_CAM")
			(pinfunction "B_{1}")
			(pintype "bidirectional")
		)
	)
	(footprint "antmicro-footprints:Resonator_SMD_Abracon_ABM8G_3.2x2.5mm"
		(layer "F.Cu")
		(at 147.248 71.732 180)
		(property "Reference" "Y1"
			(at -1.75 -1.75 0)
			(layer "F.SilkS")
			(effects
				(font
					(size 0.7 0.7)
					(thickness 0.15)
				)
				(justify left bottom)
			)
		)
		(property "Value" "Resonator_25MHz_ABM8G"
			(at -1.75 2.548 180)
			(layer "F.Fab")
			(effects
				(font
					(size 0.7 0.7)
					(thickness 0.15)
				)
				(justify left bottom)
			)
		)
		(property "Datasheet" "https://abracon.com/Resonators/ABM8G.pdf"
			(at 0 0 180)
			(layer "F.Fab")
			(hide yes)
			(effects
				(font
					(size 1.27 1.27)
					(thickness 0.15)
				)
			)
		)
		(property "Description" "Crystal, 25 MHz, SMD, 3.2mm x 2.5mm, 30 ppm, 18 pF, 20 ppm, ABM8G"
			(at 0 0 180)
			(layer "F.Fab")
			(hide yes)
			(effects
				(font
					(size 1.27 1.27)
					(thickness 0.15)
				)
			)
		)
		(property "Author" "Antmicro"
			(at 294.496 143.464 0)
			(layer "F.Fab")
			(hide yes)
			(effects
				(font
					(size 1 1)
					(thickness 0.15)
				)
			)
		)
		(property "License" "Apache-2.0"
			(at 294.496 143.464 0)
			(layer "F.Fab")
			(hide yes)
			(effects
				(font
					(size 1 1)
					(thickness 0.15)
				)
			)
		)
		(property "MPN" "ABM8G-25.000MHZ-18-D2Y-T3"
			(at 294.496 143.464 0)
			(layer "F.Fab")
			(hide yes)
			(effects
				(font
					(size 1 1)
					(thickness 0.15)
				)
			)
		)
		(property "Manufacturer" "Abracon"
			(at 294.496 143.464 0)
			(layer "F.Fab")
			(hide yes)
			(effects
				(font
					(size 1 1)
					(thickness 0.15)
				)
			)
		)
		(property "Val" "25 MHz"
			(at 294.496 143.464 0)
			(layer "F.Fab")
			(hide yes)
			(effects
				(font
					(size 1 1)
					(thickness 0.15)
				)
			)
		)
		(sheetname "/Deserializer/")
		(sheetfile "deserializer.kicad_sch")
		(attr smd)
		(fp_line
			(start 1.6 0.3)
			(end 1.6 -0.2)
			(stroke
				(width 0.15)
				(type solid)
			)
			(layer "F.SilkS")
		)
		(fp_line
			(start -0.35 1.25)
			(end 0.45 1.25)
			(stroke
				(width 0.15)
				(type solid)
			)
			(layer "F.SilkS")
		)
		(fp_line
			(start -0.35 -1.25)
			(end 0.45 -1.25)
			(stroke
				(width 0.15)
				(type solid)
			)
			(layer "F.SilkS")
		)
		(fp_line
			(start -1.6 0.3)
			(end -1.6 -0.2)
			(stroke
				(width 0.15)
				(type solid)
			)
			(layer "F.SilkS")
		)
		(fp_circle
			(center -1.75 1.5)
			(end -1.7 1.5)
			(stroke
				(width 0.15)
				(type solid)
			)
			(fill no)
			(layer "F.SilkS")
		)
		(fp_rect
			(start -1.907 -1.55)
			(end 2.006 1.649)
			(stroke
				(width 0.05)
				(type solid)
			)
			(fill no)
			(layer "F.CrtYd")
		)
		(pad "1" smd roundrect
			(at -1.101 0.949 180)
			(size 1.3 1.1)
			(layers "F.Cu" "F.Mask" "F.Paste")
			(roundrect_rratio 0)
			(chamfer_ratio 0.2)
			(chamfer bottom_left)
			(net 12 "/Deserializer/X1")
			(pintype "passive")
		)
		(pad "2" smd rect
			(at 1.199 0.949 180)
			(size 1.3 1.1)
			(layers "F.Cu" "F.Mask" "F.Paste")
			(net 1 "GND")
			(pinfunction "SH")
			(pintype "passive")
		)
		(pad "3" smd rect
			(at 1.199 -0.85 180)
			(size 1.3 1.1)
			(layers "F.Cu" "F.Mask" "F.Paste")
			(net 17 "/Deserializer/X2_R")
			(pintype "passive")
		)
		(pad "4" smd rect
			(at -1.101 -0.85 180)
			(size 1.3 1.1)
			(layers "F.Cu" "F.Mask" "F.Paste")
			(net 1 "GND")
			(pinfunction "SH")
			(pintype "passive")
		)
	)
	(footprint "antmicro-footprints:TP_SMD_0.75mm"
		(layer "F.Cu")
		(at 152.4 97.89)
		(property "Reference" "TP6"
			(at 0 -0.6 0)
			(layer "F.SilkS")
			(hide yes)
			(effects
				(font
					(size 0.7 0.7)
					(thickness 0.15)
				)
				(justify left bottom)
			)
		)
		(property "Value" "TP_0.75mm_SMD"
			(at 0 1.2 0)
			(layer "F.Fab")
			(effects
				(font
					(size 0.7 0.7)
					(thickness 0.15)
				)
				(justify left bottom)
			)
		)
		(property "Description" "SMT test point"
			(at 0 0 0)
			(layer "F.Fab")
			(hide yes)
			(effects
				(font
					(size 1.27 1.27)
					(thickness 0.15)
				)
			)
		)
		(property "Author" "Antmicro"
			(at 0 0 0)
			(layer "F.Fab")
			(hide yes)
			(effects
				(font
					(size 1 1)
					(thickness 0.15)
				)
			)
		)
		(property "License" "Apache-2.0"
			(at 0 0 0)
			(layer "F.Fab")
			(hide yes)
			(effects
				(font
					(size 1 1)
					(thickness 0.15)
				)
			)
		)
		(property "MPN" ""
			(at 0 0 0)
			(layer "F.Fab")
			(hide yes)
			(effects
				(font
					(size 1 1)
					(thickness 0.15)
				)
			)
		)
		(property "Manufacturer" ""
			(at 0 0 0)
			(layer "F.Fab")
			(hide yes)
			(effects
				(font
					(size 1 1)
					(thickness 0.15)
				)
			)
		)
		(sheetname "/Connectors/")
		(sheetfile "connectors.kicad_sch")
		(fp_circle
			(center 0 0)
			(end 0.475 0)
			(stroke
				(width 0.05)
				(type default)
			)
			(fill no)
			(layer "F.CrtYd")
		)
		(pad "1" smd circle
			(at 0 0)
			(size 0.75 0.75)
			(layers "F.Cu" "F.Mask")
			(net 2 "/Connectors/DC_UNFUSED")
			(pinfunction "1")
			(pintype "passive")
		)
	)
	(footprint "antmicro-footprints:LED_0603_1608Metric_G"
		(layer "F.Cu")
		(at 146.3 96.09 90)
		(descr "LED SMD 0603 Green")
		(tags "LED SMD 0603 Green")
		(property "Reference" "D19"
			(at 5.41111 -27.883333 180)
			(layer "F.SilkS")
			(effects
				(font
					(size 0.7 0.7)
					(thickness 0.15)
				)
				(justify right bottom)
			)
		)
		(property "Value" "LED_G_0603_LTST-C190GKT"
			(at -0.001 1.599 90)
			(layer "F.Fab")
			(effects
				(font
					(size 0.7 0.7)
					(thickness 0.15)
				)
				(justify left bottom)
			)
		)
		(property "Datasheet" "https://media.digikey.com/pdf/Data%20Sheets/Lite-On%20PDFs/LTST-C190GKT.pdf"
			(at 0 0 90)
			(layer "F.Fab")
			(hide yes)
			(effects
				(font
					(size 1.27 1.27)
					(thickness 0.15)
				)
			)
		)
		(property "Description" "LED, Green, SMD, 0603, 20 mA, 2.1 V, 569 nm"
			(at 0 0 90)
			(layer "F.Fab")
			(hide yes)
			(effects
				(font
					(size 1.27 1.27)
					(thickness 0.15)
				)
			)
		)
		(property "Author" "Antmicro"
			(at 242.39 -50.21 0)
			(layer "F.Fab")
			(hide yes)
			(effects
				(font
					(size 1 1)
					(thickness 0.15)
				)
			)
		)
		(property "Color" "Green"
			(at 242.39 -50.21 0)
			(layer "F.Fab")
			(hide yes)
			(effects
				(font
					(size 1 1)
					(thickness 0.15)
				)
			)
		)
		(property "License" "Apache-2.0"
			(at 242.39 -50.21 0)
			(layer "F.Fab")
			(hide yes)
			(effects
				(font
					(size 1 1)
					(thickness 0.15)
				)
			)
		)
		(property "MPN" "LTST-C190GKT"
			(at 242.39 -50.21 0)
			(layer "F.Fab")
			(hide yes)
			(effects
				(font
					(size 1 1)
					(thickness 0.15)
				)
			)
		)
		(property "Manufacturer" "Lite-On"
			(at 242.39 -50.21 0)
			(layer "F.Fab")
			(hide yes)
			(effects
				(font
					(size 1 1)
					(thickness 0.15)
				)
			)
		)
		(property "VSD_class" "LED"
			(at 242.39 -50.21 0)
			(layer "F.Fab")
			(hide yes)
			(effects
				(font
					(size 1 1)
					(thickness 0.15)
				)
			)
		)
		(sheetname "/Power/")
		(sheetfile "power.kicad_sch")
		(attr smd)
		(fp_line
			(start 0.22 -0.35)
			(end -0.22 -0.35)
			(stroke
				(width 0.15)
				(type solid)
			)
			(layer "F.SilkS")
		)
		(fp_line
			(start -1.18 -0.319)
			(end -1.18 0.321)
			(stroke
				(width 0.15)
				(type solid)
			)
			(layer "F.SilkS")
		)
		(fp_line
			(start 0.105328 0.001008)
			(end 0.24 0.001)
			(stroke
				(width 0.1)
				(type solid)
			)
			(layer "F.SilkS")
		)
		(fp_line
			(start -0.094672 0.001008)
			(end 0.105328 -0.198992)
			(stroke
				(width 0.1)
				(type solid)
			)
			(layer "F.SilkS")
		)
		(fp_line
			(start -0.094672 0.001008)
			(end -0.24 0.001008)
			(stroke
				(width 0.1)
				(type solid)
			)
			(layer "F.SilkS")
		)
		(fp_line
			(start 0.105328 0.201008)
			(end 0.105328 -0.198992)
			(stroke
				(width 0.1)
				(type solid)
			)
			(layer "F.SilkS")
		)
		(fp_line
			(start 0.105328 0.201008)
			(end -0.094672 0.001008)
			(stroke
				(width 0.1)
				(type solid)
			)
			(layer "F.SilkS")
		)
		(fp_line
			(start -0.094672 0.201008)
			(end -0.094672 -0.198992)
			(stroke
				(width 0.1)
				(type solid)
			)
			(layer "F.SilkS")
		)
		(fp_line
			(start 0.22 0.35)
			(end -0.22 0.35)
			(stroke
				(width 0.15)
				(type solid)
			)
			(layer "F.SilkS")
		)
		(fp_rect
			(start 1.25 0.65)
			(end -1.25 -0.65)
			(stroke
				(width 0.05)
				(type solid)
			)
			(fill no)
			(layer "F.CrtYd")
		)
		(fp_line
			(start 0.201 -0.202)
			(end -0.101 0)
			(stroke
				(width 0.15)
				(type solid)
			)
			(layer "F.Fab")
		)
		(fp_line
			(start -0.199 -0.202)
			(end -0.199 0.1)
			(stroke
				(width 0.15)
				(type solid)
			)
			(layer "F.Fab")
		)
		(fp_line
			(start 0.599 0)
			(end 0.201 0)
			(stroke
				(width 0.15)
				(type solid)
			)
			(layer "F.Fab")
		)
		(fp_line
			(start 0.201 0)
			(end 0.201 -0.202)
			(stroke
				(width 0.15)
				(type solid)
			)
			(layer "F.Fab")
		)
		(fp_line
			(start -0.101 0)
			(end 0.201 0.2)
			(stroke
				(width 0.15)
				(type solid)
			)
			(layer "F.Fab")
		)
		(fp_line
			(start -0.199 0)
			(end -0.597 0)
			(stroke
				(width 0.15)
				(type solid)
			)
			(layer "F.Fab")
		)
		(fp_line
			(start 0.201 0.2)
			(end 0.201 0)
			(stroke
				(width 0.15)
				(type solid)
			)
			(layer "F.Fab")
		)
		(fp_line
			(start -0.199 0.2)
			(end -0.199 0.1)
			(stroke
				(width 0.15)
				(type solid)
			)
			(layer "F.Fab")
		)
		(fp_rect
			(start 0.848 0.4)
			(end -0.85 -0.402)
			(stroke
				(width 0.15)
				(type solid)
			)
			(fill no)
			(layer "F.Fab")
		)
		(pad "1" smd roundrect
			(at -0.7 0 270)
			(size 0.8 1)
			(layers "F.Cu" "F.Mask" "F.Paste")
			(roundrect_rratio 0.2)
			(net 143 "Net-(D19-C)")
			(pinfunction "C")
			(pintype "passive")
		)
		(pad "2" smd roundrect
			(at 0.7 0 270)
			(size 0.8 1)
			(layers "F.Cu" "F.Mask" "F.Paste")
			(roundrect_rratio 0.2)
			(net 144 "Net-(D19-A)")
			(pinfunction "A")
			(pintype "passive")
		)
	)
	(footprint "antmicro-footprints:C_0402_1005Metric"
		(layer "F.Cu")
		(at 151.892 75.438 45)
		(descr "Capacitor SMD 0402")
		(tags "capacitor SMD 0402")
		(property "Reference" "C34"
			(at 4.003639 0.193747 45)
			(layer "F.SilkS")
			(effects
				(font
					(size 0.7 0.7)
					(thickness 0.15)
				)
				(justify left bottom)
			)
		)
		(property "Value" "C_100n_0402"
			(at -1.022927 2.155213 45)
			(layer "F.Fab")
			(effects
				(font
					(size 0.7 0.7)
					(thickness 0.15)
				)
				(justify left bottom)
			)
		)
		(property "Datasheet" "https://www.murata.com/products/productdetail?partno=GRM155R61H104KE14%23"
			(at 0 0 45)
			(layer "F.Fab")
			(hide yes)
			(effects
				(font
					(size 1.27 1.27)
					(thickness 0.15)
				)
			)
		)
		(property "Description" "SMD Multilayer Ceramic Capacitor, 0.1 µF, 50 V, 0402 [1005 Metric], ± 10%, X5R, GRM Series"
			(at 0 0 45)
			(layer "F.Fab")
			(hide yes)
			(effects
				(font
					(size 1.27 1.27)
					(thickness 0.15)
				)
			)
		)
		(property "Author" "Antmicro"
			(at 97.830859 -85.308584 0)
			(layer "F.Fab")
			(hide yes)
			(effects
				(font
					(size 1 1)
					(thickness 0.15)
				)
			)
		)
		(property "Dielectric" "X5R"
			(at 97.830859 -85.308584 0)
			(layer "F.Fab")
			(hide yes)
			(effects
				(font
					(size 1 1)
					(thickness 0.15)
				)
			)
		)
		(property "License" "Apache-2.0"
			(at 97.830859 -85.308584 0)
			(layer "F.Fab")
			(hide yes)
			(effects
				(font
					(size 1 1)
					(thickness 0.15)
				)
			)
		)
		(property "MPN" "GRM155R61H104KE14D"
			(at 97.830859 -85.308584 0)
			(layer "F.Fab")
			(hide yes)
			(effects
				(font
					(size 1 1)
					(thickness 0.15)
				)
			)
		)
		(property "Manufacturer" "Murata"
			(at 97.830859 -85.308584 0)
			(layer "F.Fab")
			(hide yes)
			(effects
				(font
					(size 1 1)
					(thickness 0.15)
				)
			)
		)
		(property "Val" "100n"
			(at 97.830859 -85.308584 0)
			(layer "F.Fab")
			(hide yes)
			(effects
				(font
					(size 1 1)
					(thickness 0.15)
				)
			)
		)
		(property "Voltage" "50V"
			(at 97.830859 -85.308584 0)
			(layer "F.Fab")
			(hide yes)
			(effects
				(font
					(size 1 1)
					(thickness 0.15)
				)
			)
		)
		(sheetname "/Deserializer/")
		(sheetfile "deserializer.kicad_sch")
		(attr smd)
		(fp_poly
			(pts
				(xy -0.925 -0.47) (xy 0.925 -0.47) (xy 0.925 0.47) (xy -0.925 0.47)
			)
			(stroke
				(width 0.05)
				(type default)
			)
			(fill no)
			(layer "F.CrtYd")
		)
		(fp_line
			(start -0.494 -0.25)
			(end 0.504 -0.25)
			(stroke
				(width 0.15)
				(type solid)
			)
			(layer "F.Fab")
		)
		(fp_line
			(start -0.494 0.248)
			(end -0.494 -0.25)
			(stroke
				(width 0.15)
				(type solid)
			)
			(layer "F.Fab")
		)
		(fp_line
			(start 0.504 -0.25)
			(end 0.504 0.248)
			(stroke
				(width 0.15)
				(type solid)
			)
			(layer "F.Fab")
		)
		(fp_line
			(start 0.504 0.248)
			(end -0.494 0.248)
			(stroke
				(width 0.15)
				(type solid)
			)
			(layer "F.Fab")
		)
		(pad "1" smd roundrect
			(at -0.48 0 45)
			(size 0.59 0.64)
			(layers "F.Cu" "F.Mask" "F.Paste")
			(roundrect_rratio 0.25)
			(net 22 "/Deserializer/SIOC_N")
			(pintype "passive")
		)
		(pad "2" smd roundrect
			(at 0.48 0 45)
			(size 0.59 0.64)
			(layers "F.Cu" "F.Mask" "F.Paste")
			(roundrect_rratio 0.25)
			(net 23 "Net-(C34-Pad2)")
			(pintype "passive")
		)
	)
)
